# BASEBOARD_FAB2 (Tioga Pass) — schematic netlist excerpt (pin names and nets, part order shuffled) for the footprints in the layout excerpt that follows; sources: Cadence DE-HDL packaged netlist, KiCad conversion of Wiwynn_Tioga_Pass_MB.brd

J4G1  SCONN288_H44441004  SCONN  pkg PIP  page 43
  \12v\(1)  = P12V_NVDIMM_ABC
  VSS(93)  = GND
  DQ(4)  = M_A_DQ<5>
  VSS(92)  = GND
  DQ(0)  = M_A_DQ<1>
  VSS(91)  = GND
  DQS9P  = M_A_DQS_DP<9>
  DQS9N  = M_A_DQS_DN<9>
  VSS(90)  = GND
  DQ(6)  = M_A_DQ<7>
  VSS(89)  = GND
  DQ(2)  = M_A_DQ<3>
  VSS(88)  = GND
  DQ(12)  = M_A_DQ<13>
  VSS(87)  = GND
  DQ(8)  = M_A_DQ<9>
  VSS(86)  = GND
  DQS10P  = M_A_DQS_DP<10>
  DQS10N  = M_A_DQS_DN<10>
  VSS(85)  = GND
  DQ(14)  = M_A_DQ<15>
  VSS(84)  = GND
  DQ(10)  = M_A_DQ<11>
  VSS(83)  = GND
  DQ(20)  = M_A_DQ<21>
  VSS(82)  = GND
  DQ(16)  = M_A_DQ<17>
  VSS(81)  = GND
  DQS11P  = M_A_DQS_DP<11>
  DQS11N  = M_A_DQS_DN<11>
  VSS(80)  = GND
  DQ(22)  = M_A_DQ<23>
  VSS(79)  = GND
  DQ(18)  = M_A_DQ<19>
  VSS(78)  = GND
  DQ(28)  = M_A_DQ<29>
  VSS(77)  = GND
  DQ(24)  = M_A_DQ<25>
  VSS(76)  = GND
  DQS12P  = M_A_DQS_DP<12>
  DQS12N  = M_A_DQS_DN<12>
  VSS(75)  = GND
  DQ(30)  = M_A_DQ<31>
  VSS(74)  = GND
  DQ(26)  = M_A_DQ<27>
  VSS(73)  = GND
  CB(4)  = M_A_ECC<5>
  VSS(72)  = GND
  CB(0)  = M_A_ECC<1>
  VSS(71)  = GND
  DQS17P  = M_A_DQS_DP<17>
  DQS17N  = M_A_DQS_DN<17>
  VSS(70)  = GND
  CB(6)  = M_A_ECC<7>
  VSS(69)  = GND
  CB(2)  = M_A_ECC<3>
  VSS(68)  = GND
  RESET_N  = M_ABC_RST_N
  VDD(25)  = PVDDQ_ABC
  CKE(0)  = M_A_CKE<0>
  VDD(24)  = PVDDQ_ABC
  ACT_N  = M_A_ACT_N
  BG(0)  = M_A_BG<0>
  VDD(23)  = PVDDQ_ABC
  A12  = M_A_MA<12>
  A9  = M_A_MA<9>
  VDD(22)  = PVDDQ_ABC
  A8  = M_A_MA<8>
  A6  = M_A_MA<6>
  VDD(21)  = PVDDQ_ABC
  A3  = M_A_MA<3>
  A1  = M_A_MA<1>
  VDD(20)  = PVDDQ_ABC
  CK0P  = M_A_CLK_DP<0>
  CK0N  = M_A_CLK_DN<0>
  VDD(19)  = PVDDQ_ABC
  VTT(1)  = PVTT_ABC
  EVENT_N  = FM_DIMM_EVENT_COD_N
  A0  = M_A_MA<0>
  VDD(18)  = PVDDQ_ABC
  BA(0)  = M_A_BA<0>
  A16_RAS_N  = M_A_MA<16>
  VDD(17)  = PVDDQ_ABC
  S0_N  = M_A_CS_N<0>
  VDD(16)  = PVDDQ_ABC
  A15_CAS_N  = M_A_MA<15>
  ODT(0)  = M_A_ODT<0>
  VDD(15)  = PVDDQ_ABC
  S1_N  = M_A_CS_N<1>
  VDD(14)  = PVDDQ_ABC
  ODT(1)  = M_A_ODT<1>
  VDD(13)  = PVDDQ_ABC
  S2_N_C(0)  = M_A_CS_N<2>
  VSS(67)  = GND
  DQ(36)  = M_A_DQ<37>
  VSS(66)  = GND
  DQ(32)  = M_A_DQ<33>
  VSS(65)  = GND
  DQS13P  = M_A_DQS_DP<13>
  DQS13N  = M_A_DQS_DN<13>
  VSS(64)  = GND
  DQ(38)  = M_A_DQ<39>
  VSS(63)  = GND
  DQ(34)  = M_A_DQ<35>
  VSS(62)  = GND
  DQ(44)  = M_A_DQ<45>
  VSS(61)  = GND
  DQ(40)  = M_A_DQ<41>
  VSS(60)  = GND
  DQS14P  = M_A_DQS_DP<14>
  DQS14N  = M_A_DQS_DN<14>
  VSS(59)  = GND
  DQ(46)  = M_A_DQ<47>
  VSS(58)  = GND
  DQ(42)  = M_A_DQ<43>
  VSS(57)  = GND
  DQ(52)  = M_A_DQ<53>
  VSS(56)  = GND
  DQ(48)  = M_A_DQ<49>
  VSS(55)  = GND
  DQS15P  = M_A_DQS_DP<15>
  DQS15N  = M_A_DQS_DN<15>
  VSS(54)  = GND
  DQ(54)  = M_A_DQ<55>
  VSS(53)  = GND
  DQ(50)  = M_A_DQ<51>
  VSS(52)  = GND
  DQ(60)  = M_A_DQ<61>
  VSS(51)  = GND
  DQ(56)  = M_A_DQ<57>
  VSS(50)  = GND
  DQS16P  = M_A_DQS_DP<16>
  DQS16N  = M_A_DQS_DN<16>
  VSS(49)  = GND
  DQ(62)  = M_A_DQ<63>
  VSS(48)  = GND
  DQ(58)  = M_A_DQ<59>
  VSS(47)  = GND
  SA(0)  = GND
  SA(1)  = GND
  SCL  = SMB_DDR_ABC_VPP_SCL
  VPP(4)  = PVPP_ABC
  VPP(3)  = PVPP_ABC
  RFU(2)  = TP_CH_A_DIMM_A0_RFU_2
  \12v\(0)  = P12V_NVDIMM_ABC
  VREFCA  = M_A_VREF
  VSS(46)  = GND
  DQ(5)  = M_A_DQ<4>
  VSS(45)  = GND
  DQ(1)  = M_A_DQ<0>
  VSS(44)  = GND
  DQS0N  = M_A_DQS_DN<0>
  DQS0P  = M_A_DQS_DP<0>
  VSS(43)  = GND
  DQ(7)  = M_A_DQ<6>
  VSS(42)  = GND
  DQ(3)  = M_A_DQ<2>
  VSS(41)  = GND
  DQ(13)  = M_A_DQ<12>
  VSS(40)  = GND
  DQ(9)  = M_A_DQ<8>
  VSS(39)  = GND
  DQS1N  = M_A_DQS_DN<1>
  DQS1P  = M_A_DQS_DP<1>
  VSS(38)  = GND
  DQ(15)  = M_A_DQ<14>
  VSS(37)  = GND
  DQ(11)  = M_A_DQ<10>
  VSS(36)  = GND
  DQ(21)  = M_A_DQ<20>
  VSS(35)  = GND
  DQ(17)  = M_A_DQ<16>
  VSS(34)  = GND
  DQS2N  = M_A_DQS_DN<2>
  DQS2P  = M_A_DQS_DP<2>
  VSS(33)  = GND
  DQ(23)  = M_A_DQ<22>
  VSS(32)  = GND
  DQ(19)  = M_A_DQ<18>
  VSS(31)  = GND
  DQ(29)  = M_A_DQ<28>
  VSS(30)  = GND
  DQ(25)  = M_A_DQ<24>
  VSS(29)  = GND
  DQS3N  = M_A_DQS_DN<3>
  DQS3P  = M_A_DQS_DP<3>
  VSS(28)  = GND
  DQ(31)  = M_A_DQ<30>
  VSS(27)  = GND
  DQ(27)  = M_A_DQ<26>
  VSS(26)  = GND
  CB(5)  = M_A_ECC<4>
  VSS(25)  = GND
  CB(1)  = M_A_ECC<0>
  VSS(24)  = GND
  DQS8N  = M_A_DQS_DN<8>
  DQS8P  = M_A_DQS_DP<8>
  VSS(23)  = GND
  CB(7)  = M_A_ECC<6>
  VSS(22)  = GND
  CB(3)  = M_A_ECC<2>
  VSS(21)  = GND
  CKE(1)  = M_A_CKE<1>
  VDD(12)  = PVDDQ_ABC
  RFU(0)  = TP_CH_A_DIMM_A0_RFU_0
  VDD(11)  = PVDDQ_ABC
  BG(1)  = M_A_BG<1>
  ALERT_N  = M_A_ALERT_N
  VDD(10)  = PVDDQ_ABC
  A11  = M_A_MA<11>
  A7  = M_A_MA<7>
  VDD(9)  = PVDDQ_ABC
  A5  = M_A_MA<5>
  A4  = M_A_MA<4>
  VDD(8)  = PVDDQ_ABC
  A2  = M_A_MA<2>
  VDD(7)  = PVDDQ_ABC
  CK1P  = M_A_CLK_DP<1>
  CK1N  = M_A_CLK_DN<1>
  VDD(6)  = PVDDQ_ABC
  VTT(0)  = PVTT_ABC
  PAR  = M_A_PAR
  VDD(5)  = PVDDQ_ABC
  BA(1)  = M_A_BA<1>
  A10  = M_A_MA<10>
  VDD(4)  = PVDDQ_ABC
  RFU(1)  = TP_CH_A_DIMM_A0_RFU_1
  A14_WE_N  = M_A_MA<14>
  VDD(3)  = PVDDQ_ABC
  SAVE_N_NC  = FM_ADR_COMPLETE_ABC_N
  VDD(2)  = PVDDQ_ABC
  A13  = M_A_MA<13>
  VDD(1)  = PVDDQ_ABC
  A17  = M_A_MA<17>
  C(2)  = M_A_C<2>
  VDD(0)  = PVDDQ_ABC
  S3_N_C(1)  = M_A_CS_N<3>
  SA(2)  = GND
  VSS(20)  = GND
  DQ(37)  = M_A_DQ<36>
  VSS(19)  = GND
  DQ(33)  = M_A_DQ<32>
  VSS(18)  = GND
  DQS4N  = M_A_DQS_DN<4>
  DQS4P  = M_A_DQS_DP<4>
  VSS(17)  = GND
  DQ(39)  = M_A_DQ<38>
  VSS(16)  = GND
  DQ(35)  = M_A_DQ<34>
  VSS(15)  = GND
  DQ(45)  = M_A_DQ<44>
  VSS(14)  = GND
  DQ(41)  = M_A_DQ<40>
  VSS(13)  = GND
  DQS5N  = M_A_DQS_DN<5>
  DQS5P  = M_A_DQS_DP<5>
  VSS(12)  = GND
  DQ(47)  = M_A_DQ<46>
  VSS(11)  = GND
  DQ(43)  = M_A_DQ<42>
  VSS(10)  = GND
  DQ(53)  = M_A_DQ<52>
  VSS(9)  = GND
  DQ(49)  = M_A_DQ<48>
  VSS(8)  = GND
  DQS6N  = M_A_DQS_DN<6>
  DQS6P  = M_A_DQS_DP<6>
  VSS(7)  = GND
  DQ(55)  = M_A_DQ<54>
  VSS(6)  = GND
  DQ(51)  = M_A_DQ<50>
  VSS(5)  = GND
  DQ(61)  = M_A_DQ<60>
  VSS(4)  = GND
  DQ(57)  = M_A_DQ<56>
  VSS(3)  = GND
  DQS7N  = M_A_DQS_DN<7>
  DQS7P  = M_A_DQS_DP<7>
  VSS(2)  = GND
  DQ(63)  = M_A_DQ<62>
  VSS(1)  = GND
  DQ(59)  = M_A_DQ<58>
  VSS(0)  = GND
  VDDSPD  = PVPP_ABC
  SDA  = SMB_DDR_ABC_VPP_SDA
  VPP(1)  = PVPP_ABC
  VPP(0)  = PVPP_ABC
  VPP(2)  = PVPP_ABC

(kicad_pcb
	(version 20260206)
	(generator "pcbnew")
	(generator_version "10.0")
	(general
		(thickness 1.6)
		(legacy_teardrops no)
	)
	(paper "A4")
	(title_block
		(title "Wiwynn_Tioga_Pass_MB.brd")
		(comment 1 "Tioga Pass / footprint 2167 of 4770 (J4G1), pads 203-251 of 291")
	)
	(layers
		(0 "F.Cu" signal "TOP")
		(4 "In1.Cu" signal "L2GND")
		(6 "In2.Cu" signal "L3")
		(8 "In3.Cu" signal "L4GND")
		(10 "In4.Cu" signal "L5")
		(12 "In5.Cu" signal "L6GND")
		(14 "In6.Cu" signal "L7VCC")
		(16 "In7.Cu" signal "L8VCC")
		(18 "In8.Cu" signal "L9GND")
		(20 "In9.Cu" signal "L10")
		(22 "In10.Cu" signal "L11GND")
		(24 "In11.Cu" signal "L12")
		(26 "In12.Cu" signal "L13GND")
		(2 "B.Cu" signal "BOTTOM")
		(9 "F.Adhes" user "F.Adhesive")
		(11 "B.Adhes" user "B.Adhesive")
		(13 "F.Paste" user "Package Geometry/Pastemask Top")
		(15 "B.Paste" user "Package Geometry/Pastemask Bottom")
		(5 "F.SilkS" user "Ref Des/Silkscreen Top")
		(7 "B.SilkS" user "Ref Des/Silkscreen Bottom")
		(1 "F.Mask" user "Board Geometry/Soldermask Top")
		(3 "B.Mask" user "Board Geometry/Soldermask Bottom")
		(17 "Dwgs.User" user "User.Drawings")
		(19 "Cmts.User" user "User.Comments")
		(21 "Eco1.User" user "User.Eco1")
		(23 "Eco2.User" user "User.Eco2")
		(25 "Edge.Cuts" user "Board Geometry/Outline")
		(27 "Margin" user)
		(31 "F.CrtYd" user "Package Geometry/Place Bound Top")
		(29 "B.CrtYd" user "Package Geometry/Place Bound Bottom")
		(35 "F.Fab" user "Ref Des/Assembly Top")
		(33 "B.Fab" user "Ref Des/Assembly Bottom")
	)
	(footprint ""
		(layer "F.Cu")
		(at 194.700398 -15.423642 90)
		(property "Reference" "J4G1"
			(at 9.060688 37.32911 0)
			(unlocked yes)
			(layer "F.SilkS")
			(effects
				(font
					(size 0.7874 0.5842)
					(thickness 0.1524)
				)
				(justify left)
			)
		)
		(property "Value" ""
			(at 0 0 90)
			(layer "F.Fab")
			(effects
				(font
					(size 1.27 1.27)
				)
			)
		)
		(duplicate_pad_numbers_are_jumpers no)
		(pad "200" smd rect
			(at 4.59994 46.74997 90)
			(size 1.8034 0.508)
			(layers "F.Cu" "F.Mask" "F.Paste")
			(net "GND")
		)
		(pad "201" smd rect
			(at 4.59994 47.600108 90)
			(size 1.8034 0.508)
			(layers "F.Cu" "F.Mask" "F.Paste")
			(net "M_A_ECC<2>")
		)
		(pad "202" smd rect
			(at 4.59994 48.449992 90)
			(size 1.8034 0.508)
			(layers "F.Cu" "F.Mask" "F.Paste")
			(net "GND")
		)
		(pad "203" smd rect
			(at 4.59994 49.299876 90)
			(size 1.8034 0.508)
			(layers "F.Cu" "F.Mask" "F.Paste")
			(net "M_A_CKE<1>")
		)
		(pad "204" smd rect
			(at 4.59994 50.150014 90)
			(size 1.8034 0.508)
			(layers "F.Cu" "F.Mask" "F.Paste")
			(net "PVDDQ_ABC")
		)
		(pad "205" smd rect
			(at 4.59994 50.999898 90)
			(size 1.8034 0.508)
			(layers "F.Cu" "F.Mask" "F.Paste")
			(net "TP_CH_A_DIMM_A0_RFU_0")
		)
		(pad "206" smd rect
			(at 4.59994 51.850036 90)
			(size 1.8034 0.508)
			(layers "F.Cu" "F.Mask" "F.Paste")
			(net "PVDDQ_ABC")
		)
		(pad "207" smd rect
			(at 4.59994 52.69992 90)
			(size 1.8034 0.508)
			(layers "F.Cu" "F.Mask" "F.Paste")
			(net "M_A_BG<1>")
		)
		(pad "208" smd rect
			(at 4.59994 53.550058 90)
			(size 1.8034 0.508)
			(layers "F.Cu" "F.Mask" "F.Paste")
			(net "M_A_ALERT_N")
		)
		(pad "209" smd rect
			(at 4.59994 54.399942 90)
			(size 1.8034 0.508)
			(layers "F.Cu" "F.Mask" "F.Paste")
			(net "PVDDQ_ABC")
		)
		(pad "210" smd rect
			(at 4.59994 55.25008 90)
			(size 1.8034 0.508)
			(layers "F.Cu" "F.Mask" "F.Paste")
			(net "M_A_MA<11>")
		)
		(pad "211" smd rect
			(at 4.59994 56.099964 90)
			(size 1.8034 0.508)
			(layers "F.Cu" "F.Mask" "F.Paste")
			(net "M_A_MA<7>")
		)
		(pad "212" smd rect
			(at 4.59994 56.950102 90)
			(size 1.8034 0.508)
			(layers "F.Cu" "F.Mask" "F.Paste")
			(net "PVDDQ_ABC")
		)
		(pad "213" smd rect
			(at 4.59994 57.799986 90)
			(size 1.8034 0.508)
			(layers "F.Cu" "F.Mask" "F.Paste")
			(net "M_A_MA<5>")
		)
		(pad "214" smd rect
			(at 4.59994 58.650124 90)
			(size 1.8034 0.508)
			(layers "F.Cu" "F.Mask" "F.Paste")
			(net "M_A_MA<4>")
		)
		(pad "215" smd rect
			(at 4.59994 59.500008 90)
			(size 1.8034 0.508)
			(layers "F.Cu" "F.Mask" "F.Paste")
			(net "PVDDQ_ABC")
		)
		(pad "216" smd rect
			(at 4.59994 60.349892 90)
			(size 1.8034 0.508)
			(layers "F.Cu" "F.Mask" "F.Paste")
			(net "M_A_MA<2>")
		)
		(pad "217" smd rect
			(at 4.59994 61.20003 90)
			(size 1.8034 0.508)
			(layers "F.Cu" "F.Mask" "F.Paste")
			(net "PVDDQ_ABC")
		)
		(pad "218" smd rect
			(at 4.59994 62.049914 90)
			(size 1.8034 0.508)
			(layers "F.Cu" "F.Mask" "F.Paste")
			(net "M_A_CLK_DP<1>")
		)
		(pad "219" smd rect
			(at 4.59994 62.900052 90)
			(size 1.8034 0.508)
			(layers "F.Cu" "F.Mask" "F.Paste")
			(net "M_A_CLK_DN<1>")
		)
		(pad "220" smd rect
			(at 4.59994 63.749936 90)
			(size 1.8034 0.508)
			(layers "F.Cu" "F.Mask" "F.Paste")
			(net "PVDDQ_ABC")
		)
		(pad "221" smd rect
			(at 4.59994 64.600074 90)
			(size 1.8034 0.508)
			(layers "F.Cu" "F.Mask" "F.Paste")
			(net "PVTT_ABC")
		)
		(pad "222" smd rect
			(at 4.59994 70.550024 90)
			(size 1.8034 0.508)
			(layers "F.Cu" "F.Mask" "F.Paste")
			(net "M_A_PAR")
		)
		(pad "223" smd rect
			(at 4.59994 71.399908 90)
			(size 1.8034 0.508)
			(layers "F.Cu" "F.Mask" "F.Paste")
			(net "PVDDQ_ABC")
		)
		(pad "224" smd rect
			(at 4.59994 72.250046 90)
			(size 1.8034 0.508)
			(layers "F.Cu" "F.Mask" "F.Paste")
			(net "M_A_BA<1>")
		)
		(pad "225" smd rect
			(at 4.59994 73.09993 90)
			(size 1.8034 0.508)
			(layers "F.Cu" "F.Mask" "F.Paste")
			(net "M_A_MA<10>")
		)
		(pad "226" smd rect
			(at 4.59994 73.950068 90)
			(size 1.8034 0.508)
			(layers "F.Cu" "F.Mask" "F.Paste")
			(net "PVDDQ_ABC")
		)
		(pad "227" smd rect
			(at 4.59994 74.799952 90)
			(size 1.8034 0.508)
			(layers "F.Cu" "F.Mask" "F.Paste")
			(net "TP_CH_A_DIMM_A0_RFU_1")
		)
		(pad "228" smd rect
			(at 4.59994 75.65009 90)
			(size 1.8034 0.508)
			(layers "F.Cu" "F.Mask" "F.Paste")
			(net "M_A_MA<14>")
		)
		(pad "229" smd rect
			(at 4.59994 76.499974 90)
			(size 1.8034 0.508)
			(layers "F.Cu" "F.Mask" "F.Paste")
			(net "PVDDQ_ABC")
		)
		(pad "230" smd rect
			(at 4.59994 77.350112 90)
			(size 1.8034 0.508)
			(layers "F.Cu" "F.Mask" "F.Paste")
			(net "FM_ADR_COMPLETE_ABC_N")
		)
		(pad "231" smd rect
			(at 4.59994 78.199996 90)
			(size 1.8034 0.508)
			(layers "F.Cu" "F.Mask" "F.Paste")
			(net "PVDDQ_ABC")
		)
		(pad "232" smd rect
			(at 4.59994 79.04988 90)
			(size 1.8034 0.508)
			(layers "F.Cu" "F.Mask" "F.Paste")
			(net "M_A_MA<13>")
		)
		(pad "233" smd rect
			(at 4.59994 79.900018 90)
			(size 1.8034 0.508)
			(layers "F.Cu" "F.Mask" "F.Paste")
			(net "PVDDQ_ABC")
		)
		(pad "234" smd rect
			(at 4.59994 80.749902 90)
			(size 1.8034 0.508)
			(layers "F.Cu" "F.Mask" "F.Paste")
			(net "M_A_MA<17>")
		)
		(pad "235" smd rect
			(at 4.59994 81.60004 90)
			(size 1.8034 0.508)
			(layers "F.Cu" "F.Mask" "F.Paste")
			(net "M_A_C<2>")
		)
		(pad "236" smd rect
			(at 4.59994 82.449924 90)
			(size 1.8034 0.508)
			(layers "F.Cu" "F.Mask" "F.Paste")
			(net "PVDDQ_ABC")
		)
		(pad "237" smd rect
			(at 4.59994 83.300062 90)
			(size 1.8034 0.508)
			(layers "F.Cu" "F.Mask" "F.Paste")
			(net "M_A_CS_N<3>")
		)
		(pad "238" smd rect
			(at 4.59994 84.149946 90)
			(size 1.8034 0.508)
			(layers "F.Cu" "F.Mask" "F.Paste")
			(net "GND")
		)
		(pad "239" smd rect
			(at 4.59994 85.000084 90)
			(size 1.8034 0.508)
			(layers "F.Cu" "F.Mask" "F.Paste")
			(net "GND")
		)
		(pad "240" smd rect
			(at 4.59994 85.849968 90)
			(size 1.8034 0.508)
			(layers "F.Cu" "F.Mask" "F.Paste")
			(net "M_A_DQ<36>")
		)
		(pad "241" smd rect
			(at 4.59994 86.700106 90)
			(size 1.8034 0.508)
			(layers "F.Cu" "F.Mask" "F.Paste")
			(net "GND")
		)
		(pad "242" smd rect
			(at 4.59994 87.54999 90)
			(size 1.8034 0.508)
			(layers "F.Cu" "F.Mask" "F.Paste")
			(net "M_A_DQ<32>")
		)
		(pad "243" smd rect
			(at 4.59994 88.399874 90)
			(size 1.8034 0.508)
			(layers "F.Cu" "F.Mask" "F.Paste")
			(net "GND")
		)
		(pad "244" smd rect
			(at 4.59994 89.250012 90)
			(size 1.8034 0.508)
			(layers "F.Cu" "F.Mask" "F.Paste")
			(net "M_A_DQS_DN<4>")
		)
		(pad "245" smd rect
			(at 4.59994 90.099896 90)
			(size 1.8034 0.508)
			(layers "F.Cu" "F.Mask" "F.Paste")
			(net "M_A_DQS_DP<4>")
		)
		(pad "246" smd rect
			(at 4.59994 90.950034 90)
			(size 1.8034 0.508)
			(layers "F.Cu" "F.Mask" "F.Paste")
			(net "GND")
		)
		(pad "247" smd rect
			(at 4.59994 91.799918 90)
			(size 1.8034 0.508)
			(layers "F.Cu" "F.Mask" "F.Paste")
			(net "M_A_DQ<38>")
		)
		(pad "248" smd rect
			(at 4.59994 92.650056 90)
			(size 1.8034 0.508)
			(layers "F.Cu" "F.Mask" "F.Paste")
			(net "GND")
		)
	)
)
